# T6G (Grand Teton) — schematic netlist excerpt (pin names and nets, part order shuffled) for the footprints in the layout excerpt that follows; sources: Cadence DE-HDL packaged netlist, KiCad conversion of 04192023_DAF0TMB3IC0_F0TG_MB_C_brd_V02_OCP.brd

X9004  TP_TDR_4P_FTS  TP_TDR_4P_DIP EMPTY  pkg TH  page 261
  S1  = TDR_DIFF_85_NECK_IN3_DP
  P1  = T1_GND
  P2  = T1_GND
  S2  = TDR_DIFF_85_NECK_IN3_DN

(kicad_pcb
	(version 20260206)
	(generator "pcbnew")
	(generator_version "10.0")
	(general
		(thickness 1.6)
		(legacy_teardrops no)
	)
	(paper "A4")
	(title_block
		(title "04192023_DAF0TMB3IC0_F0TG_MB_C_brd_V02_OCP.brd")
		(comment 1 "Grand Teton / footprints 1000-1000 of 8354")
	)
	(layers
		(0 "F.Cu" signal "TOP")
		(4 "In1.Cu" signal "GND")
		(6 "In2.Cu" signal "IN1")
		(8 "In3.Cu" signal "GND1")
		(10 "In4.Cu" signal "IN2")
		(12 "In5.Cu" signal "GND2")
		(14 "In6.Cu" signal "IN3")
		(16 "In7.Cu" signal "GND3")
		(18 "In8.Cu" signal "VCC")
		(20 "In9.Cu" signal "VCC1")
		(22 "In10.Cu" signal "GND4")
		(24 "In11.Cu" signal "IN4")
		(26 "In12.Cu" signal "GND5")
		(28 "In13.Cu" signal "IN5")
		(30 "In14.Cu" signal "GND6")
		(32 "In15.Cu" signal "IN6")
		(34 "In16.Cu" signal "GND7")
		(2 "B.Cu" signal "BOTTOM")
		(9 "F.Adhes" user "F.Adhesive")
		(11 "B.Adhes" user "B.Adhesive")
		(13 "F.Paste" user "Package Geometry/Pastemask Top")
		(15 "B.Paste" user "Package Geometry/Pastemask Bottom")
		(5 "F.SilkS" user "Ref Des/Silkscreen Top")
		(7 "B.SilkS" user "Ref Des/Silkscreen Bottom")
		(1 "F.Mask" user "Board Geometry/Soldermask Top")
		(3 "B.Mask" user "Board Geometry/Soldermask Bottom")
		(17 "Dwgs.User" user "User.Drawings")
		(19 "Cmts.User" user "User.Comments")
		(21 "Eco1.User" user "User.Eco1")
		(23 "Eco2.User" user "User.Eco2")
		(25 "Edge.Cuts" user "Board Geometry/Outline")
		(27 "Margin" user)
		(31 "F.CrtYd" user "Package Geometry/Place Bound Top")
		(29 "B.CrtYd" user "Package Geometry/Place Bound Bottom")
		(35 "F.Fab" user "Ref Des/Assembly Top")
		(33 "B.Fab" user "Ref Des/Assembly Bottom")
	)
	(footprint ""
		(layer "F.Cu")
		(at 482.294946 -457.301092 90)
		(property "Reference" "X9004"
			(at -2.091182 1.02362 0)
			(unlocked yes)
			(layer "F.SilkS")
			(effects
				(font
					(size 0.7874 0.5842)
					(thickness 0.1524)
				)
				(justify left)
			)
		)
		(property "Value" ""
			(at 0 0 90)
			(layer "F.Fab")
			(effects
				(font
					(size 1.27 1.27)
				)
			)
		)
		(property "User Part Number" "N_A"
			(at 1.30175 1.27 180)
			(unlocked yes)
			(layer "Cmts.User")
			(hide yes)
			(effects
				(font
					(size 0.635 0.4064)
					(thickness 0.1524)
				)
			)
		)
		(property "Device Type" "TP_TDR_4P_FTS_TH-TP_TDR_4P_DIP,EMPTY,TP15"
			(at 1.30175 1.27 180)
			(unlocked yes)
			(layer "F.Fab")
			(hide yes)
			(effects
				(font
					(size 0.635 0.4064)
					(thickness 0.1524)
				)
			)
		)
		(duplicate_pad_numbers_are_jumpers no)
		(fp_line
			(start 2.54 -1.27)
			(end 0 -1.27)
			(stroke
				(width 0.1524)
				(type default)
			)
			(layer "F.SilkS")
		)
		(fp_line
			(start 0 -1.27)
			(end 0 -0.635)
			(stroke
				(width 0.1524)
				(type default)
			)
			(layer "F.SilkS")
		)
		(fp_line
			(start 2.54 -1.1303)
			(end 2.54 -1.27)
			(stroke
				(width 0.1524)
				(type default)
			)
			(layer "F.SilkS")
		)
		(fp_line
			(start 0 0.635)
			(end 0 1.905)
			(stroke
				(width 0.1524)
				(type default)
			)
			(layer "F.SilkS")
		)
		(fp_line
			(start 2.54 1.4097)
			(end 2.54 1.1303)
			(stroke
				(width 0.1524)
				(type default)
			)
			(layer "F.SilkS")
		)
		(fp_line
			(start 0 3.175)
			(end 0 3.81)
			(stroke
				(width 0.1524)
				(type default)
			)
			(layer "F.SilkS")
		)
		(fp_line
			(start 2.54 3.81)
			(end 2.54 3.6703)
			(stroke
				(width 0.1524)
				(type default)
			)
			(layer "F.SilkS")
		)
		(fp_line
			(start 0 3.81)
			(end 2.54 3.81)
			(stroke
				(width 0.1524)
				(type default)
			)
			(layer "F.SilkS")
		)
		(fp_poly
			(pts
				(xy -2.285746 -0.762) (xy -0.761746 0) (xy -2.285746 0.762)
			)
			(stroke
				(width 0)
				(type default)
			)
			(fill yes)
			(layer "F.SilkS")
		)
		(fp_line
			(start 2.54 -1.27)
			(end 0 -1.27)
			(stroke
				(width 0.1)
				(type default)
			)
			(layer "F.Fab")
		)
		(fp_line
			(start 0 -1.27)
			(end 0 3.81)
			(stroke
				(width 0.1)
				(type default)
			)
			(layer "F.Fab")
		)
		(fp_line
			(start 2.54 3.81)
			(end 2.54 -1.27)
			(stroke
				(width 0.1)
				(type default)
			)
			(layer "F.Fab")
		)
		(fp_line
			(start 0 3.81)
			(end 2.54 3.81)
			(stroke
				(width 0.1)
				(type default)
			)
			(layer "F.Fab")
		)
		(fp_poly
			(pts
				(xy -0.761746 0) (xy -2.285746 -0.762) (xy -2.285746 0.762)
			)
			(stroke
				(width 0)
				(type default)
			)
			(fill yes)
			(layer "F.Fab")
		)
		(pad "1" thru_hole circle
			(at 0 0 90)
			(size 1.0033 1.0033)
			(drill 0.249936)
			(layers "*.Cu" "*.Mask")
			(remove_unused_layers no)
			(net "TDR_DIFF_85_NECK_IN3_DP")
			(clearance 0.10795)
			(thermal_gap 0.10795)
			(padstack
				(mode front_inner_back)
				(layer "Inner"
					(shape circle)
					(size 0.8001 0.8001)
					(clearance 0.1524)
				)
				(layer "B.Cu"
					(shape circle)
					(size 1.0033 1.0033)
					(clearance 0.10795)
				)
			)
		)
		(pad "2" thru_hole circle
			(at 2.54 0 90)
			(size 1.9939 1.9939)
			(drill 0.249936)
			(layers "*.Cu" "*.Mask")
			(remove_unused_layers no)
			(net "T1_GND")
			(clearance 0.10795)
			(thermal_gap 0.10795)
			(padstack
				(mode front_inner_back)
				(layer "Inner"
					(shape circle)
					(size 0.8001 0.8001)
					(clearance 0.1524)
				)
				(layer "B.Cu"
					(shape circle)
					(size 1.9939 1.9939)
					(clearance 0.10795)
				)
			)
		)
		(pad "3" thru_hole circle
			(at 2.54 2.54 90)
			(size 1.9939 1.9939)
			(drill 0.249936)
			(layers "*.Cu" "*.Mask")
			(remove_unused_layers no)
			(net "T1_GND")
			(clearance 0.10795)
			(thermal_gap 0.10795)
			(padstack
				(mode front_inner_back)
				(layer "Inner"
					(shape circle)
					(size 0.8001 0.8001)
					(clearance 0.1524)
				)
				(layer "B.Cu"
					(shape circle)
					(size 1.9939 1.9939)
					(clearance 0.10795)
				)
			)
		)
		(pad "4" thru_hole circle
			(at 0 2.54 90)
			(size 1.0033 1.0033)
			(drill 0.249936)
			(layers "*.Cu" "*.Mask")
			(remove_unused_layers no)
			(net "TDR_DIFF_85_NECK_IN3_DN")
			(clearance 0.10795)
			(thermal_gap 0.10795)
			(padstack
				(mode front_inner_back)
				(layer "Inner"
					(shape circle)
					(size 0.8001 0.8001)
					(clearance 0.1524)
				)
				(layer "B.Cu"
					(shape circle)
					(size 1.0033 1.0033)
					(clearance 0.10795)
				)
			)
		)
	)
)
